# BASEBOARD_FAB2 (Tioga Pass) — schematic netlist excerpt (pin names and nets, part order shuffled) for the footprints in the layout excerpt that follows; sources: Cadence DE-HDL packaged netlist, KiCad conversion of Wiwynn_Tioga_Pass_MB.brd

C2A7  CAP_A  47UF 4V 20% X5R  pkg 0603V  page 228 : A = PVDDQ_KLM ; B = GND
C5D20  CAP_A  22.0UF 4V 20% X6S  pkg 0603V  page 42 : A = PVCCMCP_CPU0 ; B = GND

(kicad_pcb
	(version 20260206)
	(generator "pcbnew")
	(generator_version "10.0")
	(general
		(thickness 1.6)
		(legacy_teardrops no)
	)
	(paper "A4")
	(title_block
		(title "Wiwynn_Tioga_Pass_MB.brd")
		(comment 1 "Tioga Pass / footprints 2258-2259 of 4770")
	)
	(layers
		(0 "F.Cu" signal "TOP")
		(4 "In1.Cu" signal "L2GND")
		(6 "In2.Cu" signal "L3")
		(8 "In3.Cu" signal "L4GND")
		(10 "In4.Cu" signal "L5")
		(12 "In5.Cu" signal "L6GND")
		(14 "In6.Cu" signal "L7VCC")
		(16 "In7.Cu" signal "L8VCC")
		(18 "In8.Cu" signal "L9GND")
		(20 "In9.Cu" signal "L10")
		(22 "In10.Cu" signal "L11GND")
		(24 "In11.Cu" signal "L12")
		(26 "In12.Cu" signal "L13GND")
		(2 "B.Cu" signal "BOTTOM")
		(9 "F.Adhes" user "F.Adhesive")
		(11 "B.Adhes" user "B.Adhesive")
		(13 "F.Paste" user "Package Geometry/Pastemask Top")
		(15 "B.Paste" user "Package Geometry/Pastemask Bottom")
		(5 "F.SilkS" user "Ref Des/Silkscreen Top")
		(7 "B.SilkS" user "Ref Des/Silkscreen Bottom")
		(1 "F.Mask" user "Board Geometry/Soldermask Top")
		(3 "B.Mask" user "Board Geometry/Soldermask Bottom")
		(17 "Dwgs.User" user "User.Drawings")
		(19 "Cmts.User" user "User.Comments")
		(21 "Eco1.User" user "User.Eco1")
		(23 "Eco2.User" user "User.Eco2")
		(25 "Edge.Cuts" user "Board Geometry/Outline")
		(27 "Margin" user)
		(31 "F.CrtYd" user "Package Geometry/Place Bound Top")
		(29 "B.CrtYd" user "Package Geometry/Place Bound Bottom")
		(35 "F.Fab" user "Ref Des/Assembly Top")
		(33 "B.Fab" user "Ref Des/Assembly Bottom")
	)
	(footprint ""
		(layer "F.Cu")
		(at 104.5591 -149.8092 90)
		(property "Reference" "C2A7"
			(at 1.848866 0.752348 90)
			(unlocked yes)
			(layer "F.SilkS")
			(effects
				(font
					(size 1.27 0.9652)
					(thickness 0.1524)
				)
			)
		)
		(property "Value" ""
			(at 0 0 90)
			(layer "F.Fab")
			(effects
				(font
					(size 1.27 1.27)
				)
			)
		)
		(duplicate_pad_numbers_are_jumpers no)
		(fp_rect
			(start -0.500126 1.598422)
			(end 0.500126 -0.201422)
			(stroke
				(width 0)
				(type default)
			)
			(fill no)
			(layer "F.CrtYd")
		)
		(fp_line
			(start 0.500126 -0.201422)
			(end 0.500126 1.598422)
			(stroke
				(width 0.1)
				(type default)
			)
			(layer "F.Fab")
		)
		(fp_line
			(start -0.500126 -0.201422)
			(end 0.500126 -0.201422)
			(stroke
				(width 0.1)
				(type default)
			)
			(layer "F.Fab")
		)
		(fp_line
			(start 0.500126 1.598422)
			(end -0.500126 1.598422)
			(stroke
				(width 0.1)
				(type default)
			)
			(layer "F.Fab")
		)
		(fp_line
			(start -0.500126 1.598422)
			(end -0.500126 -0.201422)
			(stroke
				(width 0.1)
				(type default)
			)
			(layer "F.Fab")
		)
		(pad "1" smd rect
			(at 0 0)
			(size 0.889 0.9906)
			(layers "F.Cu" "F.Mask" "F.Paste")
			(net "PVDDQ_KLM")
		)
		(pad "2" smd rect
			(at 0 1.397)
			(size 0.889 0.9906)
			(layers "F.Cu" "F.Mask" "F.Paste")
			(net "GND")
		)
		(zone
			(layer "F.Cu")
			(hatch none 0.5)
			(connect_pads
				(clearance 0)
			)
			(min_thickness 0.25)
			(keepout
				(tracks not_allowed)
				(vias allowed)
				(pads allowed)
				(copperpour not_allowed)
				(footprints allowed)
			)
			(placement
				(enabled no)
				(sheetname "")
			)
			(fill
				(thermal_gap 0.5)
				(thermal_bridge_width 0.5)
				(island_removal_mode 0)
			)
			(polygon
				(pts
					(xy 105.5116 -149.3139) (xy 105.5116 -150.3045) (xy 105.0036 -150.3045) (xy 105.0036 -149.3139)
				)
			)
		)
		(zone
			(layer "F.Cu")
			(hatch none 0.5)
			(connect_pads
				(clearance 0)
			)
			(min_thickness 0.25)
			(keepout
				(tracks allowed)
				(vias not_allowed)
				(pads allowed)
				(copperpour not_allowed)
				(footprints allowed)
			)
			(placement
				(enabled no)
				(sheetname "")
			)
			(fill
				(thermal_gap 0.5)
				(thermal_bridge_width 0.5)
				(island_removal_mode 0)
			)
			(polygon
				(pts
					(xy 105.5116 -149.3139) (xy 105.5116 -150.3045) (xy 105.0036 -150.3045) (xy 105.0036 -149.3139)
				)
			)
		)
	)
	(footprint ""
		(layer "F.Cu")
		(at 270.7132 -79.6036 180)
		(property "Reference" "C5D20"
			(at 0 0 180)
			(layer "F.SilkS")
			(hide yes)
			(effects
				(font
					(size 1.27 1.27)
				)
			)
		)
		(property "Value" ""
			(at 0 0 180)
			(layer "F.Fab")
			(effects
				(font
					(size 1.27 1.27)
				)
			)
		)
		(duplicate_pad_numbers_are_jumpers no)
		(fp_poly
			(pts
				(xy -0.4953 -0.2032) (xy 0.4953 -0.2032) (xy 0.4953 1.6002) (xy -0.4953 1.6002)
			)
			(stroke
				(width 0)
				(type default)
			)
			(fill no)
			(layer "F.CrtYd")
		)
		(fp_line
			(start 0.4953 1.6002)
			(end -0.4953 1.6002)
			(stroke
				(width 0.1)
				(type default)
			)
			(layer "F.Fab")
		)
		(fp_line
			(start 0.4953 -0.2032)
			(end 0.4953 1.6002)
			(stroke
				(width 0.1)
				(type default)
			)
			(layer "F.Fab")
		)
		(fp_line
			(start -0.4953 1.6002)
			(end -0.4953 -0.2032)
			(stroke
				(width 0.1)
				(type default)
			)
			(layer "F.Fab")
		)
		(fp_line
			(start -0.4953 -0.2032)
			(end 0.4953 -0.2032)
			(stroke
				(width 0.1)
				(type default)
			)
			(layer "F.Fab")
		)
		(pad "1" smd rect
			(at 0 0 180)
			(size 0.762 0.889)
			(layers "F.Cu" "F.Mask" "F.Paste")
			(net "PVCCMCP_CPU0")
		)
		(pad "2" smd rect
			(at 0 1.397 180)
			(size 0.762 0.889)
			(layers "F.Cu" "F.Mask" "F.Paste")
			(net "GND")
		)
		(zone
			(layer "F.Cu")
			(hatch none 0.5)
			(connect_pads
				(clearance 0)
			)
			(min_thickness 0.25)
			(keepout
				(tracks not_allowed)
				(vias allowed)
				(pads allowed)
				(copperpour not_allowed)
				(footprints allowed)
			)
			(placement
				(enabled no)
				(sheetname "")
			)
			(fill
				(thermal_gap 0.5)
				(thermal_bridge_width 0.5)
				(island_removal_mode 0)
			)
			(polygon
				(pts
					(xy 271.0942 -80.0481) (xy 270.3322 -80.0481) (xy 270.3322 -80.5561) (xy 271.0942 -80.5561)
				)
			)
		)
	)
)
